# T6G (Grand Teton) — schematic netlist excerpt (pin names and nets, part order shuffled) for the footprints in the layout excerpt that follows; sources: Cadence DE-HDL packaged netlist, KiCad conversion of 04192023_DAF0TMB3IC0_F0TG_MB_C_brd_V02_OCP.brd

J68  SCONN288_DDR506112002KQ  IO  pkg DDR288S_1-1VXC  page 95
  VIN_BULK0  = P12V_MEM_CPU0
  RFU0  = NC
  VIN_MGMT  = P3V3_AUX
  HSCL  = I3C_SPD_DDRJ_CPU0_SCL
  HSDA  = I3C_SPD_DDRJ_CPU0_SDA
  VSS0  = GND
  DQ0_A  = M_J_CPU0_SA_DQ<0>
  VSS1  = GND
  DQ1_A  = M_J_CPU0_SA_DQ<1>
  VSS2  = GND
  DQS0_A_T  = M_J_CPU0_SA_DQS_DP<0>
  DQS0_A_C  = M_J_CPU0_SA_DQS_DN<0>
  VSS3  = GND
  DQ4_A  = M_J_CPU0_SA_DQ<4>
  VSS4  = GND
  DQ5_A  = M_J_CPU0_SA_DQ<5>
  VSS5  = GND
  DQ8_A  = M_J_CPU0_SA_DQ<8>
  VSS6  = GND
  DQ9_A  = M_J_CPU0_SA_DQ<9>
  VSS7  = GND
  DQS1_A_T  = M_J_CPU0_SA_DQS_DP<1>
  DQS1_A_C  = M_J_CPU0_SA_DQS_DN<1>
  VSS8  = GND
  DQ12_A  = M_J_CPU0_SA_DQ<12>
  VSS9  = GND
  DQ13_A  = M_J_CPU0_SA_DQ<13>
  VSS10  = GND
  DQ16_A  = M_J_CPU0_SA_DQ<16>
  VSS11  = GND
  DQ17_A  = M_J_CPU0_SA_DQ<17>
  VSS12  = GND
  DQS2_A_T  = M_J_CPU0_SA_DQS_DP<2>
  DQS2_A_C  = M_J_CPU0_SA_DQS_DN<2>
  VSS13  = GND
  DQ20_A  = M_J_CPU0_SA_DQ<20>
  VSS14  = GND
  DQ21_A  = M_J_CPU0_SA_DQ<21>
  VSS15  = GND
  DQ24_A  = M_J_CPU0_SA_DQ<24>
  VSS16  = GND
  DQ25_A  = M_J_CPU0_SA_DQ<25>
  VSS17  = GND
  DQS3_A_T  = M_J_CPU0_SA_DQS_DP<3>
  DQS3_A_C  = M_J_CPU0_SA_DQS_DN<3>
  VSS18  = GND
  DQ28_A  = M_J_CPU0_SA_DQ<28>
  VSS19  = GND
  DQ29_A  = M_J_CPU0_SA_DQ<29>
  VSS20  = GND
  CB0_A  = M_J_CPU0_SA_CB<0>
  VSS21  = GND
  CB1_A  = M_J_CPU0_SA_CB<1>
  VSS22  = GND
  DQS4_A_T  = M_J_CPU0_SA_DQS_DP<4>
  DQS4_A_C  = M_J_CPU0_SA_DQS_DN<4>
  VSS23  = GND
  CB4_A  = M_J_CPU0_SA_CB<4>
  VSS24  = GND
  CB5_A  = M_J_CPU0_SA_CB<5>
  VSS25  = GND
  ALERT_N  = M_J_CPU0_ALERT_N
  VSS26  = GND
  CS0_A_N  = M_J_CPU0_SA_CS_N<0>
  VSS27  = GND
  CA0_A  = M_J_CPU0_SA_CA<0>
  VSS28  = GND
  CA2_A  = M_J_CPU0_SA_CA<2>
  VSS29  = GND
  CA4_A  = M_J_CPU0_SA_CA<4>
  VSS30  = GND
  CA6_A  = M_J_CPU0_SA_CA<6>
  VSS31  = GND
  PAR_A  = M_J_CPU0_SA_PAR
  VSS32  = GND
  CA0_B  = M_J_CPU0_SB_CA<0>
  VSS33  = GND
  CA2_B  = M_J_CPU0_SB_CA<2>
  VSS34  = GND
  CA4_B  = M_J_CPU0_SB_CA<4>
  VSS35  = GND
  CA6_B  = M_J_CPU0_SB_CA<6>
  VSS36  = GND
  CS0_B_N  = M_J_CPU0_SB_CS_N<0>
  VSS37  = GND
  \lbd||rsp_a_n\  = M_J_CPU0_SA_RSP<0>
  \lbs||rsp_b_n\  = M_J_CPU0_SB_RSP<0>
  VSS38  = GND
  CB4_B  = M_J_CPU0_SB_CB<4>
  VSS39  = GND
  CB5_B  = M_J_CPU0_SB_CB<5>
  VSS40  = GND
  \dqs9_b_t||tdqs9_b_t||dbi4_b_n\  = M_J_CPU0_SB_DQS_DP<9>
  \dqs9_b_c||tdqs9_b_c\  = M_J_CPU0_SB_DQS_DN<9>
  VSS41  = GND
  CB0_B  = M_J_CPU0_SB_CB<0>
  VSS42  = GND
  CB1_B  = M_J_CPU0_SB_CB<1>
  VSS43  = GND
  DQ0_B  = M_J_CPU0_SB_DQ<0>
  VSS44  = GND
  DQ1_B  = M_J_CPU0_SB_DQ<1>
  VSS45  = GND
  DQS0_B_T  = M_J_CPU0_SB_DQS_DP<0>
  DQS0_B_C  = M_J_CPU0_SB_DQS_DN<0>
  VSS46  = GND
  DQ4_B  = M_J_CPU0_SB_DQ<4>
  VSS47  = GND
  DQ5_B  = M_J_CPU0_SB_DQ<5>
  VSS48  = GND
  DQ8_B  = M_J_CPU0_SB_DQ<8>
  VSS49  = GND
  DQ9_B  = M_J_CPU0_SB_DQ<9>
  VSS50  = GND
  DQS1_B_T  = M_J_CPU0_SB_DQS_DP<1>
  DQS1_B_C  = M_J_CPU0_SB_DQS_DN<1>
  VSS51  = GND
  DQ12_B  = M_J_CPU0_SB_DQ<12>
  VSS52  = GND
  DQ13_B  = M_J_CPU0_SB_DQ<13>
  VSS53  = GND
  DQ16_B  = M_J_CPU0_SB_DQ<16>
  VSS54  = GND
  DQ17_B  = M_J_CPU0_SB_DQ<17>
  VSS55  = GND
  DQS2_B_T  = M_J_CPU0_SB_DQS_DP<2>
  DQS2_B_C  = M_J_CPU0_SB_DQS_DN<2>
  VSS56  = GND
  DQ20_B  = M_J_CPU0_SB_DQ<20>
  VSS57  = GND
  DQ21_B  = M_J_CPU0_SB_DQ<21>
  VSS58  = GND
  DQ24_B  = M_J_CPU0_SB_DQ<24>
  VSS59  = GND
  DQ25_B  = M_J_CPU0_SB_DQ<25>
  VSS60  = GND
  DQS3_B_T  = M_J_CPU0_SB_DQS_DP<3>
  DQS3_B_C  = M_J_CPU0_SB_DQS_DN<3>
  VSS61  = GND
  DQ28_B  = M_J_CPU0_SB_DQ<28>
  VSS62  = GND
  DQ29_B  = M_J_CPU0_SB_DQ<29>
  VSS63  = GND
  RFU1  = NC
  VIN_BULK1  = P12V_MEM_CPU0
  VIN_BULK2  = P12V_MEM_CPU0
  \pwr_good||fail_n\  = PWRGD_CHJ_CPU0_DIMM
  HAS  = PD_CHJ_CPU0_DIMM_SAA
  RFU2  = NC
  RFU3  = NC
  VSS64  = GND
  DQ2_A  = M_J_CPU0_SA_DQ<2>
  VSS65  = GND
  DQ3_A  = M_J_CPU0_SA_DQ<3>
  VSS66  = GND
  \dqs5_a_c||tdqs5_a_c||dqs5_a_t||tdqs5_a_t\  = M_J_CPU0_SA_DQS_DN<5>
  \dqs5_a_t||tdqs5_a_t\  = M_J_CPU0_SA_DQS_DP<5>
  VSS67  = GND
  DQ6_A  = M_J_CPU0_SA_DQ<6>
  VSS68  = GND
  DQ7_A  = M_J_CPU0_SA_DQ<7>
  VSS69  = GND
  DQ10_A  = M_J_CPU0_SA_DQ<10>
  VSS70  = GND
  DQ11_A  = M_J_CPU0_SA_DQ<11>
  VSS71  = GND
  \dqs6_a_c||tdqs6_a_c||dqs6_a_t||tdqs6_a_t\  = M_J_CPU0_SA_DQS_DN<6>
  \dqs6_a_t||tdqs6_a_t\  = M_J_CPU0_SA_DQS_DP<6>
  VSS72  = GND
  DQ14_A  = M_J_CPU0_SA_DQ<14>
  VSS73  = GND
  DQ15_A  = M_J_CPU0_SA_DQ<15>
  VSS74  = GND
  DQ18_A  = M_J_CPU0_SA_DQ<18>
  VSS75  = GND
  DQ19_A  = M_J_CPU0_SA_DQ<19>
  VSS76  = GND
  \dqs7_a_c||tdqs7_a_c\  = M_J_CPU0_SA_DQS_DN<7>
  \dqs7_a_t||tdqs7_a_t\  = M_J_CPU0_SA_DQS_DP<7>
  VSS77  = GND
  DQ22_A  = M_J_CPU0_SA_DQ<22>
  VSS78  = GND
  DQ23_A  = M_J_CPU0_SA_DQ<23>
  VSS79  = GND
  DQ26_A  = M_J_CPU0_SA_DQ<26>
  VSS80  = GND
  DQ27_A  = M_J_CPU0_SA_DQ<27>
  VSS81  = GND
  \dqs8_a_c||tdqs8_a_c\  = M_J_CPU0_SA_DQS_DN<8>
  \dqs8_a_t||tdqs8_a_t\  = M_J_CPU0_SA_DQS_DP<8>
  VSS82  = GND
  DQ30_A  = M_J_CPU0_SA_DQ<30>
  VSS83  = GND
  DQ31_A  = M_J_CPU0_SA_DQ<31>
  VSS84  = GND
  CB2_A  = M_J_CPU0_SA_CB<2>
  VSS85  = GND
  CB3_A  = M_J_CPU0_SA_CB<3>
  VSS86  = GND
  \dqs9_a_c||tdqs9_a_c\  = M_J_CPU0_SA_DQS_DN<9>
  \dqs9_a_t||tdqs9_a_t\  = M_J_CPU0_SA_DQS_DP<9>
  VSS87  = GND
  CB6_A  = M_J_CPU0_SA_CB<6>
  VSS88  = GND
  CB7_A  = M_J_CPU0_SA_CB<7>
  VSS89  = GND
  RESET_N  = M_J_CPU0_RESET_N
  VSS90  = GND
  CS1_A_N  = M_J_CPU0_SA_CS_N<1>
  VSS91  = GND
  CA1_A  = M_J_CPU0_SA_CA<1>
  VSS92  = GND
  CA3_A  = M_J_CPU0_SA_CA<3>
  VSS93  = GND
  CA5_A  = M_J_CPU0_SA_CA<5>
  VSS94  = GND
  CK_T  = M_J_CPU0_CLK_DP<0>
  CK_C  = M_J_CPU0_CLK_DN<0>
  VSS95  = GND
  RFU4  = NC
  CA1_B  = M_J_CPU0_SB_CA<1>
  VSS96  = GND
  CA3_B  = M_J_CPU0_SB_CA<3>
  VSS97  = GND
  CA5_B  = M_J_CPU0_SB_CA<5>
  VSS98  = GND
  PAR_B  = M_J_CPU0_SB_PAR
  VSS99  = GND
  CS1_B_N  = M_J_CPU0_SB_CS_N<1>
  VSS100  = GND
  RFU5  = NC
  RFU6  = NC
  VSS101  = GND
  CB6_B  = M_J_CPU0_SB_CB<6>
  VSS102  = GND
  CB7_B  = M_J_CPU0_SB_CB<7>
  VSS103  = GND
  DQS4_B_C  = M_J_CPU0_SB_DQS_DN<4>
  DQS4_B_T  = M_J_CPU0_SB_DQS_DP<4>
  VSS104  = GND
  CB2_B  = M_J_CPU0_SB_CB<2>
  VSS105  = GND
  CB3_B  = M_J_CPU0_SB_CB<3>
  VSS106  = GND
  DQ2_B  = M_J_CPU0_SB_DQ<2>
  VSS107  = GND
  DQ3_B  = M_J_CPU0_SB_DQ<3>
  VSS108  = GND
  \dqs5_b_c||tdqs5_b_c\  = M_J_CPU0_SB_DQS_DN<5>
  \dqs5_b_t||tdqs5_b_t\  = M_J_CPU0_SB_DQS_DP<5>
  VSS109  = GND
  DQ6_B  = M_J_CPU0_SB_DQ<6>
  VSS110  = GND
  DQ7_B  = M_J_CPU0_SB_DQ<7>
  VSS111  = GND
  DQ10_B  = M_J_CPU0_SB_DQ<10>
  VSS112  = GND
  DQ11_B  = M_J_CPU0_SB_DQ<11>
  VSS113  = GND
  \dqs6_b_c||tdqs6_b_c\  = M_J_CPU0_SB_DQS_DN<6>
  \dqs6_b_t||tdqs6_b_t\  = M_J_CPU0_SB_DQS_DP<6>
  VSS114  = GND
  DQ14_B  = M_J_CPU0_SB_DQ<14>
  VSS115  = GND
  DQ15_B  = M_J_CPU0_SB_DQ<15>
  VSS116  = GND
  DQ18_B  = M_J_CPU0_SB_DQ<18>
  VSS117  = GND
  DQ19_B  = M_J_CPU0_SB_DQ<19>
  VSS118  = GND
  \dqs7_b_c||tdqs7_b_c\  = M_J_CPU0_SB_DQS_DN<7>
  \dqs7_b_t||tdqs7_b_t\  = M_J_CPU0_SB_DQS_DP<7>
  VSS119  = GND
  DQ22_B  = M_J_CPU0_SB_DQ<22>
  VSS120  = GND
  DQ23_B  = M_J_CPU0_SB_DQ<23>
  VSS121  = GND
  DQ26_B  = M_J_CPU0_SB_DQ<26>
  VSS122  = GND
  DQ27_B  = M_J_CPU0_SB_DQ<27>
  VSS123  = GND
  \dqs8_b_c||tdqs8_b_c\  = M_J_CPU0_SB_DQS_DN<8>
  \dqs8_b_t||tdqs8_b_t\  = M_J_CPU0_SB_DQS_DP<8>
  VSS124  = GND
  DQ30_B  = M_J_CPU0_SB_DQ<30>
  VSS125  = GND
  DQ31_B  = M_J_CPU0_SB_DQ<31>
  VSS126  = GND
  G1  = GND
  G2  = GND
  G3  = GND

(kicad_pcb
	(version 20260206)
	(generator "pcbnew")
	(generator_version "10.0")
	(general
		(thickness 1.6)
		(legacy_teardrops no)
	)
	(paper "A4")
	(title_block
		(title "04192023_DAF0TMB3IC0_F0TG_MB_C_brd_V02_OCP.brd")
		(comment 1 "Grand Teton / footprint 802 of 8354 (J68), pads 276-291 of 291")
	)
	(layers
		(0 "F.Cu" signal "TOP")
		(4 "In1.Cu" signal "GND")
		(6 "In2.Cu" signal "IN1")
		(8 "In3.Cu" signal "GND1")
		(10 "In4.Cu" signal "IN2")
		(12 "In5.Cu" signal "GND2")
		(14 "In6.Cu" signal "IN3")
		(16 "In7.Cu" signal "GND3")
		(18 "In8.Cu" signal "VCC")
		(20 "In9.Cu" signal "VCC1")
		(22 "In10.Cu" signal "GND4")
		(24 "In11.Cu" signal "IN4")
		(26 "In12.Cu" signal "GND5")
		(28 "In13.Cu" signal "IN5")
		(30 "In14.Cu" signal "GND6")
		(32 "In15.Cu" signal "IN6")
		(34 "In16.Cu" signal "GND7")
		(2 "B.Cu" signal "BOTTOM")
		(9 "F.Adhes" user "F.Adhesive")
		(11 "B.Adhes" user "B.Adhesive")
		(13 "F.Paste" user "Package Geometry/Pastemask Top")
		(15 "B.Paste" user "Package Geometry/Pastemask Bottom")
		(5 "F.SilkS" user "Ref Des/Silkscreen Top")
		(7 "B.SilkS" user "Ref Des/Silkscreen Bottom")
		(1 "F.Mask" user "Board Geometry/Soldermask Top")
		(3 "B.Mask" user "Board Geometry/Soldermask Bottom")
		(17 "Dwgs.User" user "User.Drawings")
		(19 "Cmts.User" user "User.Comments")
		(21 "Eco1.User" user "User.Eco1")
		(23 "Eco2.User" user "User.Eco2")
		(25 "Edge.Cuts" user "Board Geometry/Outline")
		(27 "Margin" user)
		(31 "F.CrtYd" user "Package Geometry/Place Bound Top")
		(29 "B.CrtYd" user "Package Geometry/Place Bound Bottom")
		(35 "F.Fab" user "Ref Des/Assembly Top")
		(33 "B.Fab" user "Ref Des/Assembly Bottom")
	)
	(footprint ""
		(layer "F.Cu")
		(at 437.05018 -255.560068 180)
		(property "Reference" "J68"
			(at 1.32334 -81.844388 0)
			(unlocked yes)
			(layer "F.SilkS")
			(effects
				(font
					(size 0.7874 0.5842)
					(thickness 0.1524)
				)
			)
		)
		(property "Value" ""
			(at 0 0 180)
			(layer "F.Fab")
			(effects
				(font
					(size 1.27 1.27)
				)
			)
		)
		(duplicate_pad_numbers_are_jumpers no)
		(pad "276" smd rect
			(at 2.050034 53.125116 90)
			(size 0.519938 1.4986)
			(layers "F.Cu" "F.Mask" "F.Paste")
			(net "M_J_CPU0_SB_DQ<23>")
		)
		(pad "277" smd rect
			(at 2.050034 53.975 90)
			(size 0.519938 1.4986)
			(layers "F.Cu" "F.Mask" "F.Paste")
			(net "GND")
		)
		(pad "278" smd rect
			(at 2.050034 54.824884 90)
			(size 0.519938 1.4986)
			(layers "F.Cu" "F.Mask" "F.Paste")
			(net "M_J_CPU0_SB_DQ<26>")
		)
		(pad "279" smd rect
			(at 2.050034 55.675022 90)
			(size 0.519938 1.4986)
			(layers "F.Cu" "F.Mask" "F.Paste")
			(net "GND")
		)
		(pad "280" smd rect
			(at 2.050034 56.524906 90)
			(size 0.519938 1.4986)
			(layers "F.Cu" "F.Mask" "F.Paste")
			(net "M_J_CPU0_SB_DQ<27>")
		)
		(pad "281" smd rect
			(at 2.050034 57.375044 90)
			(size 0.519938 1.4986)
			(layers "F.Cu" "F.Mask" "F.Paste")
			(net "GND")
		)
		(pad "282" smd rect
			(at 2.050034 58.224928 90)
			(size 0.519938 1.4986)
			(layers "F.Cu" "F.Mask" "F.Paste")
			(net "M_J_CPU0_SB_DQS_DN<8>")
		)
		(pad "283" smd rect
			(at 2.050034 59.075066 90)
			(size 0.519938 1.4986)
			(layers "F.Cu" "F.Mask" "F.Paste")
			(net "M_J_CPU0_SB_DQS_DP<8>")
		)
		(pad "284" smd rect
			(at 2.050034 59.92495 90)
			(size 0.519938 1.4986)
			(layers "F.Cu" "F.Mask" "F.Paste")
			(net "GND")
		)
		(pad "285" smd rect
			(at 2.050034 60.775088 90)
			(size 0.519938 1.4986)
			(layers "F.Cu" "F.Mask" "F.Paste")
			(net "M_J_CPU0_SB_DQ<30>")
		)
		(pad "286" smd rect
			(at 2.050034 61.624972 90)
			(size 0.519938 1.4986)
			(layers "F.Cu" "F.Mask" "F.Paste")
			(net "GND")
		)
		(pad "287" smd rect
			(at 2.050034 62.47511 90)
			(size 0.519938 1.4986)
			(layers "F.Cu" "F.Mask" "F.Paste")
			(net "M_J_CPU0_SB_DQ<31>")
		)
		(pad "288" smd rect
			(at 2.050034 63.324994 90)
			(size 0.519938 1.4986)
			(layers "F.Cu" "F.Mask" "F.Paste")
			(net "GND")
		)
		(pad "G1" thru_hole oval
			(at 0 -68.97497 90)
			(size 1.7272 3.4798)
			(drill oval 1.2192 2.4638)
			(layers "*.Cu" "*.Mask")
			(remove_unused_layers no)
			(net "GND")
			(clearance 0.127)
			(thermal_gap 0.127)
		)
		(pad "G2" thru_hole oval
			(at 0 3.875024 90)
			(size 1.7272 3.4798)
			(drill oval 1.2192 2.4638)
			(layers "*.Cu" "*.Mask")
			(remove_unused_layers no)
			(net "GND")
			(clearance 0.127)
			(thermal_gap 0.127)
		)
		(pad "G3" thru_hole oval
			(at 0 68.97497 90)
			(size 1.7272 3.4798)
			(drill oval 1.2192 2.4638)
			(layers "*.Cu" "*.Mask")
			(remove_unused_layers no)
			(net "GND")
			(clearance 0.127)
			(thermal_gap 0.127)
		)
	)
)
